(kicad_pcb
	(version 20260206)
	(generator "pcbnew")
	(generator_version "10.0")
	(general
		(thickness 1.6)
		(legacy_teardrops no)
	)
	(paper "A4")
	(title_block
		(title "04192023_DAF0TMB3IC0_F0TG_MB_C_brd_V02_OCP.brd")
		(comment 1 "Grand Teton / footprints 2485-2493 of 8354")
	)
	(layers
		(0 "F.Cu" signal "TOP")
		(4 "In1.Cu" signal "GND")
		(6 "In2.Cu" signal "IN1")
		(8 "In3.Cu" signal "GND1")
		(10 "In4.Cu" signal "IN2")
		(12 "In5.Cu" signal "GND2")
		(14 "In6.Cu" signal "IN3")
		(16 "In7.Cu" signal "GND3")
		(18 "In8.Cu" signal "VCC")
		(20 "In9.Cu" signal "VCC1")
		(22 "In10.Cu" signal "GND4")
		(24 "In11.Cu" signal "IN4")
		(26 "In12.Cu" signal "GND5")
		(28 "In13.Cu" signal "IN5")
		(30 "In14.Cu" signal "GND6")
		(32 "In15.Cu" signal "IN6")
		(34 "In16.Cu" signal "GND7")
		(2 "B.Cu" signal "BOTTOM")
		(9 "F.Adhes" user "F.Adhesive")
		(11 "B.Adhes" user "B.Adhesive")
		(13 "F.Paste" user "Package Geometry/Pastemask Top")
		(15 "B.Paste" user "Package Geometry/Pastemask Bottom")
		(5 "F.SilkS" user "Ref Des/Silkscreen Top")
		(7 "B.SilkS" user "Ref Des/Silkscreen Bottom")
		(1 "F.Mask" user "Board Geometry/Soldermask Top")
		(3 "B.Mask" user "Board Geometry/Soldermask Bottom")
		(17 "Dwgs.User" user "User.Drawings")
		(19 "Cmts.User" user "User.Comments")
		(21 "Eco1.User" user "User.Eco1")
		(23 "Eco2.User" user "User.Eco2")
		(25 "Edge.Cuts" user "Board Geometry/Outline")
		(27 "Margin" user)
		(31 "F.CrtYd" user "Package Geometry/Place Bound Top")
		(29 "B.CrtYd" user "Package Geometry/Place Bound Bottom")
		(35 "F.Fab" user "Ref Des/Assembly Top")
		(33 "B.Fab" user "Ref Des/Assembly Bottom")
	)
	(footprint ""
		(layer "F.Cu")
		(at 49.61763 -360.025696 90)
		(property "Reference" "PL49"
			(at 4.310634 -1.48463 0)
			(unlocked yes)
			(layer "F.SilkS")
			(effects
				(font
					(size 0.7874 0.5842)
					(thickness 0.1524)
				)
				(justify left)
			)
		)
		(property "Value" ""
			(at 0 0 90)
			(layer "F.Fab")
			(effects
				(font
					(size 1.27 1.27)
				)
			)
		)
		(duplicate_pad_numbers_are_jumpers no)
		(fp_line
			(start 3.050032 -2.999994)
			(end -3.050032 -2.999994)
			(stroke
				(width 0.1524)
				(type default)
			)
			(layer "F.SilkS")
		)
		(fp_line
			(start -3.050032 -2.999994)
			(end -3.050032 -1.4478)
			(stroke
				(width 0.1524)
				(type default)
			)
			(layer "F.SilkS")
		)
		(fp_line
			(start 3.050032 -1.4478)
			(end 3.050032 -2.999994)
			(stroke
				(width 0.1524)
				(type default)
			)
			(layer "F.SilkS")
		)
		(fp_line
			(start -3.050032 1.4478)
			(end -3.050032 2.999994)
			(stroke
				(width 0.1524)
				(type default)
			)
			(layer "F.SilkS")
		)
		(fp_line
			(start 3.050032 2.999994)
			(end 3.050032 1.4478)
			(stroke
				(width 0.1524)
				(type default)
			)
			(layer "F.SilkS")
		)
		(fp_line
			(start -3.050032 2.999994)
			(end 3.050032 2.999994)
			(stroke
				(width 0.1524)
				(type default)
			)
			(layer "F.SilkS")
		)
		(fp_line
			(start 3.050032 -2.999994)
			(end -3.050032 -2.999994)
			(stroke
				(width 0.1)
				(type default)
			)
			(layer "F.Fab")
		)
		(fp_line
			(start -3.050032 -2.999994)
			(end -3.050032 2.999994)
			(stroke
				(width 0.1)
				(type default)
			)
			(layer "F.Fab")
		)
		(fp_line
			(start 3.050032 2.999994)
			(end 3.050032 -2.999994)
			(stroke
				(width 0.1)
				(type default)
			)
			(layer "F.Fab")
		)
		(fp_line
			(start -3.050032 2.999994)
			(end 3.050032 2.999994)
			(stroke
				(width 0.1)
				(type default)
			)
			(layer "F.Fab")
		)
		(pad "1" smd rect
			(at -2.525014 0 90)
			(size 1.651 2.6162)
			(layers "F.Cu" "F.Mask" "F.Paste")
			(net "SW_P12V_AUX_PVDDIO_P1_FLT")
		)
		(pad "2" smd rect
			(at 2.525014 0 90)
			(size 1.651 2.6162)
			(layers "F.Cu" "F.Mask" "F.Paste")
			(net "P12V_AUX")
		)
	)
	(footprint ""
		(layer "F.Cu")
		(at 425.36872 -387.853428)
		(property "Reference" "C839"
			(at 0 0 0)
			(layer "F.SilkS")
			(hide yes)
			(effects
				(font
					(size 1.27 1.27)
				)
			)
		)
		(property "Value" ""
			(at 0 0 0)
			(layer "F.Fab")
			(effects
				(font
					(size 1.27 1.27)
				)
			)
		)
		(duplicate_pad_numbers_are_jumpers no)
		(fp_line
			(start -0.299974 -0.150114)
			(end 0.299974 -0.150114)
			(stroke
				(width 0.1)
				(type default)
			)
			(layer "F.Fab")
		)
		(fp_line
			(start -0.299974 0.150114)
			(end -0.299974 -0.150114)
			(stroke
				(width 0.1)
				(type default)
			)
			(layer "F.Fab")
		)
		(fp_line
			(start 0.299974 -0.150114)
			(end 0.299974 0.150114)
			(stroke
				(width 0.1)
				(type default)
			)
			(layer "F.Fab")
		)
		(fp_line
			(start 0.299974 0.150114)
			(end -0.299974 0.150114)
			(stroke
				(width 0.1)
				(type default)
			)
			(layer "F.Fab")
		)
		(pad "1" smd rect
			(at -0.2667 0)
			(size 0.3048 0.381)
			(layers "F.Cu" "F.Mask" "F.Paste")
			(net "P5E_CPU0_P2_TX_C_DP<15>")
		)
		(pad "2" smd rect
			(at 0.2667 0)
			(size 0.3048 0.381)
			(layers "F.Cu" "F.Mask" "F.Paste")
			(net "P5E_CPU0_P2_TX_DP<15>")
		)
	)
	(footprint ""
		(layer "F.Cu")
		(at 61.88075 -193.594228)
		(property "Reference" "TP19"
			(at 0 0 0)
			(layer "F.SilkS")
			(hide yes)
			(effects
				(font
					(size 1.27 1.27)
				)
			)
		)
		(property "Value" ""
			(at 0 0 0)
			(layer "F.Fab")
			(effects
				(font
					(size 1.27 1.27)
				)
			)
		)
		(duplicate_pad_numbers_are_jumpers no)
		(pad "1" smd circle
			(at 0 0)
			(size 0.762 0.762)
			(layers "F.Cu" "F.Mask" "F.Paste")
			(net "VSENSE_PVDD18_S5_P1_DP")
		)
	)
	(footprint ""
		(layer "F.Cu")
		(at 296.515028 -146.202908 180)
		(property "Reference" "R1297"
			(at 0 0 180)
			(layer "F.SilkS")
			(hide yes)
			(effects
				(font
					(size 1.27 1.27)
				)
			)
		)
		(property "Value" ""
			(at 0 0 180)
			(layer "F.Fab")
			(effects
				(font
					(size 1.27 1.27)
				)
			)
		)
		(duplicate_pad_numbers_are_jumpers no)
		(fp_line
			(start 0.7874 0.4064)
			(end -0.7874 0.4064)
			(stroke
				(width 0.1524)
				(type default)
			)
			(layer "F.SilkS")
		)
		(fp_line
			(start 0.7874 -0.4064)
			(end 0.7874 0.4064)
			(stroke
				(width 0.1524)
				(type default)
			)
			(layer "F.SilkS")
		)
		(fp_line
			(start -0.7874 0.4064)
			(end -0.7874 -0.4064)
			(stroke
				(width 0.1524)
				(type default)
			)
			(layer "F.SilkS")
		)
		(fp_line
			(start -0.7874 -0.4064)
			(end 0.7874 -0.4064)
			(stroke
				(width 0.1524)
				(type default)
			)
			(layer "F.SilkS")
		)
		(fp_line
			(start 0.67945 0.3048)
			(end 0.120396 0.3048)
			(stroke
				(width 0.1)
				(type default)
			)
			(layer "F.Fab")
		)
		(fp_line
			(start 0.67945 -0.3048)
			(end 0.67945 0.3048)
			(stroke
				(width 0.1)
				(type default)
			)
			(layer "F.Fab")
		)
		(fp_line
			(start 0.12065 -0.2794)
			(end 0.12065 -0.3048)
			(stroke
				(width 0.1)
				(type default)
			)
			(layer "F.Fab")
		)
		(fp_line
			(start 0.12065 -0.3048)
			(end 0.67945 -0.3048)
			(stroke
				(width 0.1)
				(type default)
			)
			(layer "F.Fab")
		)
		(fp_line
			(start 0.120396 0.3048)
			(end 0.120396 0.2794)
			(stroke
				(width 0.1)
				(type default)
			)
			(layer "F.Fab")
		)
		(fp_line
			(start 0.120396 0.2794)
			(end -0.12065 0.2794)
			(stroke
				(width 0.1)
				(type default)
			)
			(layer "F.Fab")
		)
		(fp_line
			(start -0.12065 0.3048)
			(end -0.67945 0.3048)
			(stroke
				(width 0.1)
				(type default)
			)
			(layer "F.Fab")
		)
		(fp_line
			(start -0.12065 0.2794)
			(end -0.12065 0.3048)
			(stroke
				(width 0.1)
				(type default)
			)
			(layer "F.Fab")
		)
		(fp_line
			(start -0.12065 -0.2794)
			(end 0.12065 -0.2794)
			(stroke
				(width 0.1)
				(type default)
			)
			(layer "F.Fab")
		)
		(fp_line
			(start -0.12065 -0.305054)
			(end -0.12065 -0.2794)
			(stroke
				(width 0.1)
				(type default)
			)
			(layer "F.Fab")
		)
		(fp_line
			(start -0.67945 0.3048)
			(end -0.67945 -0.305054)
			(stroke
				(width 0.1)
				(type default)
			)
			(layer "F.Fab")
		)
		(fp_line
			(start -0.67945 -0.305054)
			(end -0.12065 -0.305054)
			(stroke
				(width 0.1)
				(type default)
			)
			(layer "F.Fab")
		)
		(pad "1" smd rect
			(at -0.40005 0)
			(size 0.4572 0.508)
			(layers "F.Cu" "F.Mask" "F.Paste")
			(net "I3C_SPD_DDRAF_CPU0_SCL")
		)
		(pad "2" smd rect
			(at 0.40005 0)
			(size 0.4572 0.508)
			(layers "F.Cu" "F.Mask" "F.Paste")
			(net "I3C_SPD_DDRAF_CPU0_LVC1_SCL")
		)
	)
	(footprint ""
		(layer "F.Cu")
		(at 386.211826 -56.1975 180)
		(property "Reference" "R1354"
			(at 0 0 180)
			(layer "F.SilkS")
			(hide yes)
			(effects
				(font
					(size 1.27 1.27)
				)
			)
		)
		(property "Value" ""
			(at 0 0 180)
			(layer "F.Fab")
			(effects
				(font
					(size 1.27 1.27)
				)
			)
		)
		(duplicate_pad_numbers_are_jumpers no)
		(fp_line
			(start 0.7874 0.4064)
			(end -0.7874 0.4064)
			(stroke
				(width 0.1524)
				(type default)
			)
			(layer "F.SilkS")
		)
		(fp_line
			(start 0.7874 -0.4064)
			(end 0.7874 0.4064)
			(stroke
				(width 0.1524)
				(type default)
			)
			(layer "F.SilkS")
		)
		(fp_line
			(start -0.7874 0.4064)
			(end -0.7874 -0.4064)
			(stroke
				(width 0.1524)
				(type default)
			)
			(layer "F.SilkS")
		)
		(fp_line
			(start -0.7874 -0.4064)
			(end 0.7874 -0.4064)
			(stroke
				(width 0.1524)
				(type default)
			)
			(layer "F.SilkS")
		)
		(fp_line
			(start 0.67945 0.3048)
			(end 0.120396 0.3048)
			(stroke
				(width 0.1)
				(type default)
			)
			(layer "F.Fab")
		)
		(fp_line
			(start 0.67945 -0.3048)
			(end 0.67945 0.3048)
			(stroke
				(width 0.1)
				(type default)
			)
			(layer "F.Fab")
		)
		(fp_line
			(start 0.12065 -0.2794)
			(end 0.12065 -0.3048)
			(stroke
				(width 0.1)
				(type default)
			)
			(layer "F.Fab")
		)
		(fp_line
			(start 0.12065 -0.3048)
			(end 0.67945 -0.3048)
			(stroke
				(width 0.1)
				(type default)
			)
			(layer "F.Fab")
		)
		(fp_line
			(start 0.120396 0.3048)
			(end 0.120396 0.2794)
			(stroke
				(width 0.1)
				(type default)
			)
			(layer "F.Fab")
		)
		(fp_line
			(start 0.120396 0.2794)
			(end -0.12065 0.2794)
			(stroke
				(width 0.1)
				(type default)
			)
			(layer "F.Fab")
		)
		(fp_line
			(start -0.12065 0.3048)
			(end -0.67945 0.3048)
			(stroke
				(width 0.1)
				(type default)
			)
			(layer "F.Fab")
		)
		(fp_line
			(start -0.12065 0.2794)
			(end -0.12065 0.3048)
			(stroke
				(width 0.1)
				(type default)
			)
			(layer "F.Fab")
		)
		(fp_line
			(start -0.12065 -0.2794)
			(end 0.12065 -0.2794)
			(stroke
				(width 0.1)
				(type default)
			)
			(layer "F.Fab")
		)
		(fp_line
			(start -0.12065 -0.305054)
			(end -0.12065 -0.2794)
			(stroke
				(width 0.1)
				(type default)
			)
			(layer "F.Fab")
		)
		(fp_line
			(start -0.67945 0.3048)
			(end -0.67945 -0.305054)
			(stroke
				(width 0.1)
				(type default)
			)
			(layer "F.Fab")
		)
		(fp_line
			(start -0.67945 -0.305054)
			(end -0.12065 -0.305054)
			(stroke
				(width 0.1)
				(type default)
			)
			(layer "F.Fab")
		)
		(pad "1" smd circle
			(at -0.40005 0 180)
			(size 0 0)
			(layers "F.Cu" "F.Mask" "F.Paste")
			(net "HDT_HDR_R_TDI")
		)
		(pad "2" smd circle
			(at 0.40005 0 180)
			(size 0 0)
			(layers "F.Cu" "F.Mask" "F.Paste")
			(net "HDT_HDR_TDI")
		)
	)
	(footprint ""
		(layer "F.Cu")
		(at 302.109378 -435.233572 -90)
		(property "Reference" "R3435"
			(at 0 0 270)
			(layer "F.SilkS")
			(hide yes)
			(effects
				(font
					(size 1.27 1.27)
				)
			)
		)
		(property "Value" ""
			(at 0 0 270)
			(layer "F.Fab")
			(effects
				(font
					(size 1.27 1.27)
				)
			)
		)
		(duplicate_pad_numbers_are_jumpers no)
		(fp_line
			(start -0.7874 0.4064)
			(end -0.7874 -0.4064)
			(stroke
				(width 0.1524)
				(type default)
			)
			(layer "F.SilkS")
		)
		(fp_line
			(start 0.7874 0.4064)
			(end -0.7874 0.4064)
			(stroke
				(width 0.1524)
				(type default)
			)
			(layer "F.SilkS")
		)
		(fp_line
			(start -0.7874 -0.4064)
			(end 0.7874 -0.4064)
			(stroke
				(width 0.1524)
				(type default)
			)
			(layer "F.SilkS")
		)
		(fp_line
			(start 0.7874 -0.4064)
			(end 0.7874 0.4064)
			(stroke
				(width 0.1524)
				(type default)
			)
			(layer "F.SilkS")
		)
		(fp_line
			(start -0.67945 0.3048)
			(end -0.67945 -0.305054)
			(stroke
				(width 0.1)
				(type default)
			)
			(layer "F.Fab")
		)
		(fp_line
			(start -0.12065 0.3048)
			(end -0.67945 0.3048)
			(stroke
				(width 0.1)
				(type default)
			)
			(layer "F.Fab")
		)
		(fp_line
			(start 0.120396 0.3048)
			(end 0.120396 0.2794)
			(stroke
				(width 0.1)
				(type default)
			)
			(layer "F.Fab")
		)
		(fp_line
			(start 0.67945 0.3048)
			(end 0.120396 0.3048)
			(stroke
				(width 0.1)
				(type default)
			)
			(layer "F.Fab")
		)
		(fp_line
			(start -0.12065 0.2794)
			(end -0.12065 0.3048)
			(stroke
				(width 0.1)
				(type default)
			)
			(layer "F.Fab")
		)
		(fp_line
			(start 0.120396 0.2794)
			(end -0.12065 0.2794)
			(stroke
				(width 0.1)
				(type default)
			)
			(layer "F.Fab")
		)
		(fp_line
			(start -0.12065 -0.2794)
			(end 0.12065 -0.2794)
			(stroke
				(width 0.1)
				(type default)
			)
			(layer "F.Fab")
		)
		(fp_line
			(start 0.12065 -0.2794)
			(end 0.12065 -0.3048)
			(stroke
				(width 0.1)
				(type default)
			)
			(layer "F.Fab")
		)
		(fp_line
			(start 0.12065 -0.3048)
			(end 0.67945 -0.3048)
			(stroke
				(width 0.1)
				(type default)
			)
			(layer "F.Fab")
		)
		(fp_line
			(start 0.67945 -0.3048)
			(end 0.67945 0.3048)
			(stroke
				(width 0.1)
				(type default)
			)
			(layer "F.Fab")
		)
		(fp_line
			(start -0.67945 -0.305054)
			(end -0.12065 -0.305054)
			(stroke
				(width 0.1)
				(type default)
			)
			(layer "F.Fab")
		)
		(fp_line
			(start -0.12065 -0.305054)
			(end -0.12065 -0.2794)
			(stroke
				(width 0.1)
				(type default)
			)
			(layer "F.Fab")
		)
		(pad "1" smd circle
			(at -0.40005 0 270)
			(size 0 0)
			(layers "F.Cu" "F.Mask" "F.Paste")
			(net "P3V3_AUX")
		)
		(pad "2" smd circle
			(at 0.40005 0 270)
			(size 0 0)
			(layers "F.Cu" "F.Mask" "F.Paste")
			(net "GPU_FPGA_OVERT")
		)
	)
	(footprint ""
		(layer "F.Cu")
		(at 406.33904 -381.41783 -90)
		(property "Reference" "C858"
			(at 0 0 270)
			(layer "F.SilkS")
			(hide yes)
			(effects
				(font
					(size 1.27 1.27)
				)
			)
		)
		(property "Value" ""
			(at 0 0 270)
			(layer "F.Fab")
			(effects
				(font
					(size 1.27 1.27)
				)
			)
		)
		(duplicate_pad_numbers_are_jumpers no)
		(fp_line
			(start -0.299974 0.150114)
			(end -0.299974 -0.150114)
			(stroke
				(width 0.1)
				(type default)
			)
			(layer "F.Fab")
		)
		(fp_line
			(start 0.299974 0.150114)
			(end -0.299974 0.150114)
			(stroke
				(width 0.1)
				(type default)
			)
			(layer "F.Fab")
		)
		(fp_line
			(start -0.299974 -0.150114)
			(end 0.299974 -0.150114)
			(stroke
				(width 0.1)
				(type default)
			)
			(layer "F.Fab")
		)
		(fp_line
			(start 0.299974 -0.150114)
			(end 0.299974 0.150114)
			(stroke
				(width 0.1)
				(type default)
			)
			(layer "F.Fab")
		)
		(pad "1" smd rect
			(at -0.2667 0 270)
			(size 0.3048 0.381)
			(layers "F.Cu" "F.Mask" "F.Paste")
			(net "P5E_CPU0_P2_TX_C_DN<5>")
		)
		(pad "2" smd rect
			(at 0.2667 0 270)
			(size 0.3048 0.381)
			(layers "F.Cu" "F.Mask" "F.Paste")
			(net "P5E_CPU0_P2_TX_DN<5>")
		)
	)
	(footprint ""
		(layer "F.Cu")
		(at 110.365794 -384.66268)
		(property "Reference" "R917"
			(at 0 0 0)
			(layer "F.SilkS")
			(hide yes)
			(effects
				(font
					(size 1.27 1.27)
				)
			)
		)
		(property "Value" ""
			(at 0 0 0)
			(layer "F.Fab")
			(effects
				(font
					(size 1.27 1.27)
				)
			)
		)
		(duplicate_pad_numbers_are_jumpers no)
		(fp_line
			(start -0.32512 -0.175006)
			(end 0.32512 -0.175006)
			(stroke
				(width 0.1)
				(type default)
			)
			(layer "F.Fab")
		)
		(fp_line
			(start -0.32512 0.175006)
			(end -0.32512 -0.175006)
			(stroke
				(width 0.1)
				(type default)
			)
			(layer "F.Fab")
		)
		(fp_line
			(start 0.32512 -0.175006)
			(end 0.32512 0.175006)
			(stroke
				(width 0.1)
				(type default)
			)
			(layer "F.Fab")
		)
		(fp_line
			(start 0.32512 0.175006)
			(end -0.32512 0.175006)
			(stroke
				(width 0.1)
				(type default)
			)
			(layer "F.Fab")
		)
		(pad "1" smd rect
			(at -0.2667 0)
			(size 0.3048 0.381)
			(layers "F.Cu" "F.Mask" "F.Paste")
			(net "GPIO3_RT_CPU1_P3")
		)
		(pad "2" smd rect
			(at 0.2667 0 180)
			(size 0.3048 0.381)
			(layers "F.Cu" "F.Mask" "F.Paste")
			(net "GND")
		)
	)
	(footprint ""
		(layer "F.Cu")
		(at 248.20753 -53.193442 90)
		(property "Reference" "PR3950"
			(at 0 0 90)
			(layer "F.SilkS")
			(hide yes)
			(effects
				(font
					(size 1.27 1.27)
				)
			)
		)
		(property "Value" ""
			(at 0 0 90)
			(layer "F.Fab")
			(effects
				(font
					(size 1.27 1.27)
				)
			)
		)
		(duplicate_pad_numbers_are_jumpers no)
		(fp_line
			(start 0.7874 -0.4064)
			(end 0.7874 0.4064)
			(stroke
				(width 0.1524)
				(type default)
			)
			(layer "F.SilkS")
		)
		(fp_line
			(start -0.7874 -0.4064)
			(end 0.7874 -0.4064)
			(stroke
				(width 0.1524)
				(type default)
			)
			(layer "F.SilkS")
		)
		(fp_line
			(start 0.7874 0.4064)
			(end -0.7874 0.4064)
			(stroke
				(width 0.1524)
				(type default)
			)
			(layer "F.SilkS")
		)
		(fp_line
			(start -0.7874 0.4064)
			(end -0.7874 -0.4064)
			(stroke
				(width 0.1524)
				(type default)
			)
			(layer "F.SilkS")
		)
		(fp_line
			(start -0.12065 -0.305054)
			(end -0.12065 -0.2794)
			(stroke
				(width 0.1)
				(type default)
			)
			(layer "F.Fab")
		)
		(fp_line
			(start -0.67945 -0.305054)
			(end -0.12065 -0.305054)
			(stroke
				(width 0.1)
				(type default)
			)
			(layer "F.Fab")
		)
		(fp_line
			(start 0.67945 -0.3048)
			(end 0.67945 0.3048)
			(stroke
				(width 0.1)
				(type default)
			)
			(layer "F.Fab")
		)
		(fp_line
			(start 0.12065 -0.3048)
			(end 0.67945 -0.3048)
			(stroke
				(width 0.1)
				(type default)
			)
			(layer "F.Fab")
		)
		(fp_line
			(start 0.12065 -0.2794)
			(end 0.12065 -0.3048)
			(stroke
				(width 0.1)
				(type default)
			)
			(layer "F.Fab")
		)
		(fp_line
			(start -0.12065 -0.2794)
			(end 0.12065 -0.2794)
			(stroke
				(width 0.1)
				(type default)
			)
			(layer "F.Fab")
		)
		(fp_line
			(start 0.120396 0.2794)
			(end -0.12065 0.2794)
			(stroke
				(width 0.1)
				(type default)
			)
			(layer "F.Fab")
		)
		(fp_line
			(start -0.12065 0.2794)
			(end -0.12065 0.3048)
			(stroke
				(width 0.1)
				(type default)
			)
			(layer "F.Fab")
		)
		(fp_line
			(start 0.67945 0.3048)
			(end 0.120396 0.3048)
			(stroke
				(width 0.1)
				(type default)
			)
			(layer "F.Fab")
		)
		(fp_line
			(start 0.120396 0.3048)
			(end 0.120396 0.2794)
			(stroke
				(width 0.1)
				(type default)
			)
			(layer "F.Fab")
		)
		(fp_line
			(start -0.12065 0.3048)
			(end -0.67945 0.3048)
			(stroke
				(width 0.1)
				(type default)
			)
			(layer "F.Fab")
		)
		(fp_line
			(start -0.67945 0.3048)
			(end -0.67945 -0.305054)
			(stroke
				(width 0.1)
				(type default)
			)
			(layer "F.Fab")
		)
		(pad "1" smd circle
			(at -0.40005 0 90)
			(size 0 0)
			(layers "F.Cu" "F.Mask" "F.Paste")
			(net "P12V_E1S_0")
		)
		(pad "2" smd circle
			(at 0.40005 0 90)
			(size 0 0)
			(layers "F.Cu" "F.Mask" "F.Paste")
			(net "P12V_E1S_AVIN_PD_0")
		)
	)
)
